(kicad_pcb
	(version 20241229)
	(generator "pcbnew")
	(generator_version "9.0")
	(general
		(thickness 1.599998)
		(legacy_teardrops no)
	)
	(paper "A4")
	(title_block
		(title "Artix - Datacenter Secure Control Module (DC-SCM)")
		(date "2024-11-06")
		(rev "1.1.3")
		(comment 9 "footprints 116-118 of 544")
	)
	(layers
		(0 "F.Cu" signal)
		(4 "In1.Cu" signal)
		(6 "In2.Cu" signal)
		(8 "In3.Cu" signal)
		(10 "In4.Cu" signal)
		(12 "In5.Cu" signal)
		(14 "In6.Cu" signal)
		(2 "B.Cu" signal)
		(9 "F.Adhes" user "F.Adhesive")
		(11 "B.Adhes" user "B.Adhesive")
		(13 "F.Paste" user)
		(15 "B.Paste" user)
		(5 "F.SilkS" user "F.Silkscreen")
		(7 "B.SilkS" user "B.Silkscreen")
		(1 "F.Mask" user)
		(3 "B.Mask" user)
		(17 "Dwgs.User" user "User.Drawings")
		(19 "Cmts.User" user "User.Comments")
		(21 "Eco1.User" user "User.Eco1")
		(23 "Eco2.User" user "User.Eco2")
		(25 "Edge.Cuts" user)
		(27 "Margin" user)
		(31 "F.CrtYd" user "F.Courtyard")
		(29 "B.CrtYd" user "B.Courtyard")
		(35 "F.Fab" user)
		(33 "B.Fab" user)
	)
	(footprint "antmicro-footprints:LED_0603_1608Metric_G"
		(layer "F.Cu")
		(at 141.025 61.165 90)
		(descr "LED SMD 0603 Green")
		(tags "LED SMD 0603 Green")
		(property "Reference" "D12"
			(at -1.435 4.775 90)
			(layer "F.SilkS")
			(effects
				(font
					(size 0.7 0.7)
					(thickness 0.15)
				)
				(justify left bottom)
			)
		)
		(property "Value" "LED_G_0603_LG_L29K-G2J1-24-Z"
			(at 0 1.6 90)
			(layer "F.Fab")
			(effects
				(font
					(size 0.7 0.7)
					(thickness 0.15)
				)
				(justify left bottom)
			)
		)
		(property "Datasheet" "https://look.ams-osram.com/m/19ee86b3ae0ee95b/original/LG-L29K.pdf"
			(at 0 0 90)
			(layer "F.Fab")
			(hide yes)
			(effects
				(font
					(size 1.27 1.27)
					(thickness 0.15)
				)
			)
		)
		(property "Description" "LED, Green, SMD, 0603, 20 mA, 1.7 V, 570 nm"
			(at 0 0 90)
			(layer "F.Fab")
			(hide yes)
			(effects
				(font
					(size 1.27 1.27)
					(thickness 0.15)
				)
			)
		)
		(property "Author" "Antmicro"
			(at 202.19 -79.86 0)
			(layer "F.Fab")
			(hide yes)
			(effects
				(font
					(size 1 1)
					(thickness 0.15)
				)
			)
		)
		(property "Color" "Green"
			(at 202.19 -79.86 0)
			(layer "F.Fab")
			(hide yes)
			(effects
				(font
					(size 1 1)
					(thickness 0.15)
				)
			)
		)
		(property "License" "Apache-2.0"
			(at 202.19 -79.86 0)
			(layer "F.Fab")
			(hide yes)
			(effects
				(font
					(size 1 1)
					(thickness 0.15)
				)
			)
		)
		(property "MPN" "LG L29K-G2J1-24-Z"
			(at 202.19 -79.86 0)
			(layer "F.Fab")
			(hide yes)
			(effects
				(font
					(size 1 1)
					(thickness 0.15)
				)
			)
		)
		(property "Manufacturer" "OSRAM"
			(at 202.19 -79.86 0)
			(layer "F.Fab")
			(hide yes)
			(effects
				(font
					(size 1 1)
					(thickness 0.15)
				)
			)
		)
		(sheetname "/FPGA banks 34-35 & CFG/")
		(sheetfile "fpga-banks-34-25-cfg.kicad_sch")
		(attr smd)
		(fp_line
			(start 0.22 -0.35)
			(end -0.22 -0.35)
			(stroke
				(width 0.15)
				(type solid)
			)
			(layer "F.SilkS")
		)
		(fp_line
			(start -1.18 -0.319)
			(end -1.18 0.321)
			(stroke
				(width 0.15)
				(type solid)
			)
			(layer "F.SilkS")
		)
		(fp_line
			(start 0.105328 0.001008)
			(end 0.24 0.001)
			(stroke
				(width 0.1)
				(type solid)
			)
			(layer "F.SilkS")
		)
		(fp_line
			(start -0.094672 0.001008)
			(end 0.105328 -0.198992)
			(stroke
				(width 0.1)
				(type solid)
			)
			(layer "F.SilkS")
		)
		(fp_line
			(start -0.094672 0.001008)
			(end -0.24 0.001008)
			(stroke
				(width 0.1)
				(type solid)
			)
			(layer "F.SilkS")
		)
		(fp_line
			(start 0.105328 0.201008)
			(end 0.105328 -0.198992)
			(stroke
				(width 0.1)
				(type solid)
			)
			(layer "F.SilkS")
		)
		(fp_line
			(start 0.105328 0.201008)
			(end -0.094672 0.001008)
			(stroke
				(width 0.1)
				(type solid)
			)
			(layer "F.SilkS")
		)
		(fp_line
			(start -0.094672 0.201008)
			(end -0.094672 -0.198992)
			(stroke
				(width 0.1)
				(type solid)
			)
			(layer "F.SilkS")
		)
		(fp_line
			(start 0.22 0.35)
			(end -0.22 0.35)
			(stroke
				(width 0.15)
				(type solid)
			)
			(layer "F.SilkS")
		)
		(fp_rect
			(start 1.25 0.65)
			(end -1.25 -0.65)
			(stroke
				(width 0.05)
				(type solid)
			)
			(fill no)
			(layer "F.CrtYd")
		)
		(fp_line
			(start 0.201 -0.202)
			(end -0.101 0)
			(stroke
				(width 0.15)
				(type solid)
			)
			(layer "F.Fab")
		)
		(fp_line
			(start -0.199 -0.202)
			(end -0.199 0.1)
			(stroke
				(width 0.15)
				(type solid)
			)
			(layer "F.Fab")
		)
		(fp_line
			(start 0.599 0)
			(end 0.201 0)
			(stroke
				(width 0.15)
				(type solid)
			)
			(layer "F.Fab")
		)
		(fp_line
			(start 0.201 0)
			(end 0.201 -0.202)
			(stroke
				(width 0.15)
				(type solid)
			)
			(layer "F.Fab")
		)
		(fp_line
			(start -0.101 0)
			(end 0.201 0.2)
			(stroke
				(width 0.15)
				(type solid)
			)
			(layer "F.Fab")
		)
		(fp_line
			(start -0.199 0)
			(end -0.597 0)
			(stroke
				(width 0.15)
				(type solid)
			)
			(layer "F.Fab")
		)
		(fp_line
			(start 0.201 0.2)
			(end 0.201 0)
			(stroke
				(width 0.15)
				(type solid)
			)
			(layer "F.Fab")
		)
		(fp_line
			(start -0.199 0.2)
			(end -0.199 0.1)
			(stroke
				(width 0.15)
				(type solid)
			)
			(layer "F.Fab")
		)
		(fp_rect
			(start 0.848 0.4)
			(end -0.85 -0.402)
			(stroke
				(width 0.15)
				(type solid)
			)
			(fill no)
			(layer "F.Fab")
		)
		(pad "1" smd roundrect
			(at -0.7 0 270)
			(size 0.8 1)
			(layers "F.Cu" "F.Mask" "F.Paste")
			(roundrect_rratio 0.2)
			(net 305 "Net-(D12-C)")
			(pinfunction "C")
			(pintype "passive")
		)
		(pad "2" smd roundrect
			(at 0.7 0 270)
			(size 0.8 1)
			(layers "F.Cu" "F.Mask" "F.Paste")
			(roundrect_rratio 0.2)
			(net 307 "Net-(D12-A)")
			(pinfunction "A")
			(pintype "passive")
		)
	)
	(footprint "antmicro-footprints:LED_0603_1608Metric_G"
		(layer "F.Cu")
		(at 143.04 61.165 90)
		(descr "LED SMD 0603 Green")
		(tags "LED SMD 0603 Green")
		(property "Reference" "D13"
			(at -1.435 3.86 90)
			(layer "F.SilkS")
			(effects
				(font
					(size 0.7 0.7)
					(thickness 0.15)
				)
				(justify left bottom)
			)
		)
		(property "Value" "LED_G_0603_LG_L29K-G2J1-24-Z"
			(at 0 1.6 90)
			(layer "F.Fab")
			(effects
				(font
					(size 0.7 0.7)
					(thickness 0.15)
				)
				(justify left bottom)
			)
		)
		(property "Datasheet" "https://look.ams-osram.com/m/19ee86b3ae0ee95b/original/LG-L29K.pdf"
			(at 0 0 90)
			(layer "F.Fab")
			(hide yes)
			(effects
				(font
					(size 1.27 1.27)
					(thickness 0.15)
				)
			)
		)
		(property "Description" "LED, Green, SMD, 0603, 20 mA, 1.7 V, 570 nm"
			(at 0 0 90)
			(layer "F.Fab")
			(hide yes)
			(effects
				(font
					(size 1.27 1.27)
					(thickness 0.15)
				)
			)
		)
		(property "Author" "Antmicro"
			(at 204.205 -81.875 0)
			(layer "F.Fab")
			(hide yes)
			(effects
				(font
					(size 1 1)
					(thickness 0.15)
				)
			)
		)
		(property "Color" "Green"
			(at 204.205 -81.875 0)
			(layer "F.Fab")
			(hide yes)
			(effects
				(font
					(size 1 1)
					(thickness 0.15)
				)
			)
		)
		(property "License" "Apache-2.0"
			(at 204.205 -81.875 0)
			(layer "F.Fab")
			(hide yes)
			(effects
				(font
					(size 1 1)
					(thickness 0.15)
				)
			)
		)
		(property "MPN" "LG L29K-G2J1-24-Z"
			(at 204.205 -81.875 0)
			(layer "F.Fab")
			(hide yes)
			(effects
				(font
					(size 1 1)
					(thickness 0.15)
				)
			)
		)
		(property "Manufacturer" "OSRAM"
			(at 204.205 -81.875 0)
			(layer "F.Fab")
			(hide yes)
			(effects
				(font
					(size 1 1)
					(thickness 0.15)
				)
			)
		)
		(sheetname "/FPGA banks 34-35 & CFG/")
		(sheetfile "fpga-banks-34-25-cfg.kicad_sch")
		(attr smd)
		(fp_line
			(start 0.22 -0.35)
			(end -0.22 -0.35)
			(stroke
				(width 0.15)
				(type solid)
			)
			(layer "F.SilkS")
		)
		(fp_line
			(start -1.18 -0.319)
			(end -1.18 0.321)
			(stroke
				(width 0.15)
				(type solid)
			)
			(layer "F.SilkS")
		)
		(fp_line
			(start 0.105328 0.001008)
			(end 0.24 0.001)
			(stroke
				(width 0.1)
				(type solid)
			)
			(layer "F.SilkS")
		)
		(fp_line
			(start -0.094672 0.001008)
			(end 0.105328 -0.198992)
			(stroke
				(width 0.1)
				(type solid)
			)
			(layer "F.SilkS")
		)
		(fp_line
			(start -0.094672 0.001008)
			(end -0.24 0.001008)
			(stroke
				(width 0.1)
				(type solid)
			)
			(layer "F.SilkS")
		)
		(fp_line
			(start 0.105328 0.201008)
			(end 0.105328 -0.198992)
			(stroke
				(width 0.1)
				(type solid)
			)
			(layer "F.SilkS")
		)
		(fp_line
			(start 0.105328 0.201008)
			(end -0.094672 0.001008)
			(stroke
				(width 0.1)
				(type solid)
			)
			(layer "F.SilkS")
		)
		(fp_line
			(start -0.094672 0.201008)
			(end -0.094672 -0.198992)
			(stroke
				(width 0.1)
				(type solid)
			)
			(layer "F.SilkS")
		)
		(fp_line
			(start 0.22 0.35)
			(end -0.22 0.35)
			(stroke
				(width 0.15)
				(type solid)
			)
			(layer "F.SilkS")
		)
		(fp_rect
			(start 1.25 0.65)
			(end -1.25 -0.65)
			(stroke
				(width 0.05)
				(type solid)
			)
			(fill no)
			(layer "F.CrtYd")
		)
		(fp_line
			(start 0.201 -0.202)
			(end -0.101 0)
			(stroke
				(width 0.15)
				(type solid)
			)
			(layer "F.Fab")
		)
		(fp_line
			(start -0.199 -0.202)
			(end -0.199 0.1)
			(stroke
				(width 0.15)
				(type solid)
			)
			(layer "F.Fab")
		)
		(fp_line
			(start 0.599 0)
			(end 0.201 0)
			(stroke
				(width 0.15)
				(type solid)
			)
			(layer "F.Fab")
		)
		(fp_line
			(start 0.201 0)
			(end 0.201 -0.202)
			(stroke
				(width 0.15)
				(type solid)
			)
			(layer "F.Fab")
		)
		(fp_line
			(start -0.101 0)
			(end 0.201 0.2)
			(stroke
				(width 0.15)
				(type solid)
			)
			(layer "F.Fab")
		)
		(fp_line
			(start -0.199 0)
			(end -0.597 0)
			(stroke
				(width 0.15)
				(type solid)
			)
			(layer "F.Fab")
		)
		(fp_line
			(start 0.201 0.2)
			(end 0.201 0)
			(stroke
				(width 0.15)
				(type solid)
			)
			(layer "F.Fab")
		)
		(fp_line
			(start -0.199 0.2)
			(end -0.199 0.1)
			(stroke
				(width 0.15)
				(type solid)
			)
			(layer "F.Fab")
		)
		(fp_rect
			(start 0.848 0.4)
			(end -0.85 -0.402)
			(stroke
				(width 0.15)
				(type solid)
			)
			(fill no)
			(layer "F.Fab")
		)
		(pad "1" smd roundrect
			(at -0.7 0 270)
			(size 0.8 1)
			(layers "F.Cu" "F.Mask" "F.Paste")
			(roundrect_rratio 0.2)
			(net 309 "Net-(D13-C)")
			(pinfunction "C")
			(pintype "passive")
		)
		(pad "2" smd roundrect
			(at 0.7 0 270)
			(size 0.8 1)
			(layers "F.Cu" "F.Mask" "F.Paste")
			(roundrect_rratio 0.2)
			(net 311 "Net-(D13-A)")
			(pinfunction "A")
			(pintype "passive")
		)
	)
	(footprint "antmicro-footprints:SOT-23-3"
		(layer "F.Cu")
		(at 121.375 68.13)
		(property "Reference" "Q14"
			(at 0.75 -0.655 0)
			(layer "F.SilkS")
			(effects
				(font
					(size 0.7 0.7)
					(thickness 0.15)
				)
				(justify left bottom)
			)
		)
		(property "Value" "2N7002_SOT-23-3"
			(at -1.9 2.7 0)
			(layer "F.Fab")
			(effects
				(font
					(size 0.7 0.7)
					(thickness 0.15)
				)
				(justify left bottom)
			)
		)
		(property "Datasheet" "https://www.onsemi.com/pub/Collateral/NDS7002A-D.PDF"
			(at 0 0 0)
			(layer "F.Fab")
			(hide yes)
			(effects
				(font
					(size 1.27 1.27)
					(thickness 0.15)
				)
			)
		)
		(property "Description" "Power MOSFET, N Channel, 60 V, 115 mA, 1.2 ohm, SOT-23, Surface Mount"
			(at 0 0 0)
			(layer "F.Fab")
			(hide yes)
			(effects
				(font
					(size 1.27 1.27)
					(thickness 0.15)
				)
			)
		)
		(property "Author" "Antmicro"
			(at 0 0 0)
			(layer "F.Fab")
			(hide yes)
			(effects
				(font
					(size 1 1)
					(thickness 0.15)
				)
			)
		)
		(property "License" "Apache-2.0"
			(at 0 0 0)
			(layer "F.Fab")
			(hide yes)
			(effects
				(font
					(size 1 1)
					(thickness 0.15)
				)
			)
		)
		(property "MPN" "2N7002"
			(at 0 0 0)
			(layer "F.Fab")
			(hide yes)
			(effects
				(font
					(size 1 1)
					(thickness 0.15)
				)
			)
		)
		(property "Manufacturer" "ON Semiconductor"
			(at 0 0 0)
			(layer "F.Fab")
			(hide yes)
			(effects
				(font
					(size 1 1)
					(thickness 0.15)
				)
			)
		)
		(sheetname "/FPGA banks 34-35 & CFG/")
		(sheetfile "fpga-banks-34-25-cfg.kicad_sch")
		(attr smd)
		(fp_line
			(start -1.45 -1.35)
			(end -0.85 -1.35)
			(stroke
				(width 0.15)
				(type solid)
			)
			(layer "F.SilkS")
		)
		(fp_line
			(start -0.85 -1.35)
			(end -0.7 -1.5)
			(stroke
				(width 0.15)
				(type solid)
			)
			(layer "F.SilkS")
		)
		(fp_line
			(start -0.7 1.5)
			(end -0.7 1.35)
			(stroke
				(width 0.15)
				(type solid)
			)
			(layer "F.SilkS")
		)
		(fp_line
			(start 0.7 -1.5)
			(end -0.7 -1.5)
			(stroke
				(width 0.15)
				(type solid)
			)
			(layer "F.SilkS")
		)
		(fp_line
			(start 0.7 -0.4)
			(end 0.7 -1.5)
			(stroke
				(width 0.15)
				(type solid)
			)
			(layer "F.SilkS")
		)
		(fp_line
			(start 0.7 0.4)
			(end 0.7 1.5)
			(stroke
				(width 0.15)
				(type solid)
			)
			(layer "F.SilkS")
		)
		(fp_line
			(start 0.7 1.5)
			(end -0.7 1.5)
			(stroke
				(width 0.15)
				(type solid)
			)
			(layer "F.SilkS")
		)
		(fp_line
			(start -1.75 -0.5)
			(end -1.75 -1.4)
			(stroke
				(width 0.05)
				(type solid)
			)
			(layer "F.CrtYd")
		)
		(fp_line
			(start -1.75 0.5)
			(end -0.85 0.5)
			(stroke
				(width 0.05)
				(type solid)
			)
			(layer "F.CrtYd")
		)
		(fp_line
			(start -1.75 1.4)
			(end -1.75 0.5)
			(stroke
				(width 0.05)
				(type solid)
			)
			(layer "F.CrtYd")
		)
		(fp_line
			(start -0.9 -1.6)
			(end -0.9 -1.4)
			(stroke
				(width 0.05)
				(type solid)
			)
			(layer "F.CrtYd")
		)
		(fp_line
			(start -0.9 -1.6)
			(end 0.825 -1.6)
			(stroke
				(width 0.05)
				(type solid)
			)
			(layer "F.CrtYd")
		)
		(fp_line
			(start -0.9 -1.4)
			(end -1.75 -1.4)
			(stroke
				(width 0.05)
				(type solid)
			)
			(layer "F.CrtYd")
		)
		(fp_line
			(start -0.85 -0.5)
			(end -1.75 -0.5)
			(stroke
				(width 0.05)
				(type solid)
			)
			(layer "F.CrtYd")
		)
		(fp_line
			(start -0.85 0.5)
			(end -0.85 -0.5)
			(stroke
				(width 0.05)
				(type solid)
			)
			(layer "F.CrtYd")
		)
		(fp_line
			(start -0.85 1.4)
			(end -1.75 1.4)
			(stroke
				(width 0.05)
				(type solid)
			)
			(layer "F.CrtYd")
		)
		(fp_line
			(start -0.85 1.65)
			(end -0.85 1.4)
			(stroke
				(width 0.05)
				(type solid)
			)
			(layer "F.CrtYd")
		)
		(fp_line
			(start 0.825 -1.6)
			(end 0.825 -0.45)
			(stroke
				(width 0.05)
				(type solid)
			)
			(layer "F.CrtYd")
		)
		(fp_line
			(start 0.825 -0.45)
			(end 1.75 -0.45)
			(stroke
				(width 0.05)
				(type solid)
			)
			(layer "F.CrtYd")
		)
		(fp_line
			(start 0.85 0.45)
			(end 0.85 1.65)
			(stroke
				(width 0.05)
				(type solid)
			)
			(layer "F.CrtYd")
		)
		(fp_line
			(start 0.85 1.65)
			(end -0.85 1.65)
			(stroke
				(width 0.05)
				(type solid)
			)
			(layer "F.CrtYd")
		)
		(fp_line
			(start 1.75 -0.45)
			(end 1.75 0.45)
			(stroke
				(width 0.05)
				(type solid)
			)
			(layer "F.CrtYd")
		)
		(fp_line
			(start 1.75 0.45)
			(end 0.85 0.45)
			(stroke
				(width 0.05)
				(type solid)
			)
			(layer "F.CrtYd")
		)
		(fp_line
			(start -0.712 -1.325)
			(end -0.712 1.523)
			(stroke
				(width 0.15)
				(type solid)
			)
			(layer "F.Fab")
		)
		(fp_line
			(start -0.712 1.519)
			(end 0.688 1.519)
			(stroke
				(width 0.15)
				(type solid)
			)
			(layer "F.Fab")
		)
		(fp_line
			(start -0.437 -1.526)
			(end -0.712 -1.325)
			(stroke
				(width 0.15)
				(type solid)
			)
			(layer "F.Fab")
		)
		(fp_line
			(start -0.437 -1.526)
			(end 0.688 -1.526)
			(stroke
				(width 0.15)
				(type solid)
			)
			(layer "F.Fab")
		)
		(fp_line
			(start 0.688 1.519)
			(end 0.688 -1.52)
			(stroke
				(width 0.15)
				(type solid)
			)
			(layer "F.Fab")
		)
		(pad "1" smd roundrect
			(at -1.1 -0.951)
			(size 1 0.6)
			(layers "F.Cu" "F.Mask" "F.Paste")
			(roundrect_rratio 0.15)
			(net 316 "USR_LED0")
			(pinfunction "G")
			(pintype "input")
		)
		(pad "2" smd roundrect
			(at -1.1 0.949)
			(size 1 0.6)
			(layers "F.Cu" "F.Mask" "F.Paste")
			(roundrect_rratio 0.15)
			(net 1 "GND")
			(pinfunction "S")
			(pintype "passive")
		)
		(pad "3" smd roundrect
			(at 1.1 -0.0005)
			(size 1 0.6)
			(layers "F.Cu" "F.Mask" "F.Paste")
			(roundrect_rratio 0.15)
			(net 284 "Net-(D11-C)")
			(pinfunction "D")
			(pintype "passive")
		)
	)
)
